#ISCELL
  mstr_misc dns *
  *
#ISCELL
  pure_quanta quanta_title_block_c *
  *
#ISCELL
  pure_quanta_power cad_note *
  *
#CELL
  pure_quanta q_res *
  page465_i1
#CELL
  pure_quanta q_inductor *
  page465_i11
#ISCELL
  pure_quanta_power p1v0 *
  page465_i12
#ISCELL
  pure_quanta_power p1v0 *
  page465_i13
#CELL
  pure_quanta q_cap *
  page465_i14
#CELL
  pure_quanta q_cap *
  page465_i15
#CELL
  pure_quanta q_cap *
  page465_i16
#CELL
  pure_quanta q_cap *
  page465_i17
#CELL
  pure_quanta q_cap *
  page465_i18
#CELL
  pure_quanta q_cap *
  page465_i19
#CELL
  pure_quanta q_res *
  page465_i2
#CELL
  pure_quanta q_cap *
  page465_i20
#CELL
  pure_quanta q_cap *
  page465_i21
#ISCELL
  pure_quanta_power universal_gnd *
  page465_i22
#CELL
  pure_quanta q_cap *
  page465_i23
#CELL
  pure_quanta q_cap *
  page465_i24
#CELL
  pure_quanta q_cap *
  page465_i25
#CELL
  pure_quanta q_cap *
  page465_i26
#CELL
  pure_quanta q_cap *
  page465_i27
#CELL
  pure_quanta q_cap *
  page465_i28
#ISCELL
  pure_quanta_power vcc_core *
  page465_i29
#ISCELL
  pure_quanta_power universal_gnd *
  page465_i3
#ISCELL
  pure_quanta_power vcc_core *
  page465_i30
#ISCELL
  pure_quanta_power universal_gnd *
  page465_i31
#CELL
  pure_quanta q_cap *
  page465_i34
#CELL
  pure_quanta q_cap *
  page465_i35
#CELL
  pure_quanta q_res *
  page465_i36
#CELL
  pure_quanta q_cap *
  page465_i37
#CELL
  pure_quanta q_cap *
  page465_i38
#CELL
  pure_quanta q_cap *
  page465_i39
#CELL
  pure_quanta q_cap *
  page465_i4
#CELL
  pure_quanta q_cap *
  page465_i40
#CELL
  pure_quanta q_cap *
  page465_i41
#CELL
  pure_quanta q_cap *
  page465_i42
#CELL
  pure_quanta q_cap *
  page465_i43
#CELL
  pure_quanta q_cap *
  page465_i44
#CELL
  pure_quanta q_cap *
  page465_i45
#CELL
  pure_quanta q_cap *
  page465_i46
#CELL
  pure_quanta q_cap *
  page465_i47
#CELL
  pure_quanta q_cap *
  page465_i48
#CELL
  pure_quanta q_cap *
  page465_i49
#ISCELL
  pure_quanta_power p1v0 *
  page465_i5
#CELL
  pure_quanta q_cap *
  page465_i50
#CELL
  pure_quanta q_cap *
  page465_i51
#CELL
  pure_quanta q_cap *
  page465_i52
#CELL
  pure_quanta q_cap *
  page465_i53
#CELL
  pure_quanta q_cap *
  page465_i54
#ISCELL
  pure_quanta_power universal_gnd *
  page465_i55
#CELL
  pure_quanta q_cap *
  page465_i56
#CELL
  pure_quanta q_cap *
  page465_i57
#CELL
  pure_quanta q_cap *
  page465_i6
#CELL
  pure_quanta q_cap *
  page465_i60
#CELL
  pure_quanta q_cap *
  page465_i61
#ISCELL
  pure_quanta_power universal_gnd *
  page465_i62
#CELL
  pure_quanta q_inductor *
  page465_i63
#CELL
  pure_quanta q_cap *
  page465_i64
#CELL
  pure_quanta q_cap *
  page465_i65
#ISCELL
  pure_quanta_power vcc_core *
  page465_i66
#CELL
  pure_quanta q_cap *
  page465_i67
#CELL
  pure_quanta q_cap *
  page465_i68
#CELL
  pure_quanta q_cap *
  page465_i69
#ISCELL
  pure_quanta_power universal_gnd *
  page465_i7
#CELL
  pure_quanta q_cap *
  page465_i70
#CELL
  pure_quanta q_cap *
  page465_i71
#CELL
  pure_quanta q_cap *
  page465_i72
#CELL
  pure_quanta q_cap *
  page465_i73
#CELL
  pure_quanta q_cap *
  page465_i74
#CELL
  pure_quanta q_cap *
  page465_i75
#CELL
  pure_quanta q_cap *
  page465_i76
#CELL
  pure_quanta q_cap *
  page465_i77
#CELL
  pure_quanta q_cap *
  page465_i78
#CELL
  pure_quanta q_cap *
  page465_i79
#CELL
  pure_quanta q_res *
  page465_i8
#CELL
  pure_quanta q_cap *
  page465_i80
#ISCELL
  pure_quanta_power universal_gnd *
  page465_i81
#CELL
  pure_quanta q_cap *
  page465_i82
#CELL
  pure_quanta q_cap *
  page465_i83
#CELL
  pure_quanta q_cap *
  page465_i84
#CELL
  pure_quanta q_cap *
  page465_i85
#CELL
  pure_quanta q_cap *
  page465_i86
#CELL
  pure_quanta q_cap *
  page465_i87
#CELL
  pure_quanta q_inductor *
  page465_i88
#CELL
  pure_quanta q_res *
  page465_i89
#CELL
  pure_quanta q_cap *
  page465_i90
#CELL
  pure_quanta q_cap *
  page465_i91
#CELL
  pure_quanta q_cap *
  page465_i92
#CELL
  pure_quanta q_cap *
  page465_i93
#CELL
  pure_quanta q_capp *
  page465_i94
#CELL
  pure_quanta q_capp *
  page465_i95
#CELL
  pure_quanta q_cap *
  page465_i96
